FILE_TYPE = CONNECTIVITY;
{Allegro Design Entry HDL 17.4-2019 S026 (4007227) 1/17/2022}
"PAGE_NUMBER" = 167;
0"NC";
1"GND\g";
2"GND\g";
3"GND\g";
4"GND\g";
5"GND\g";
6"GND\g";
7"PVDD_33_S5_VCC\g";
8"GND\g";
9"GND\g";
10"GND\g";
11"FM_PWRGD_PVDD33_S5";
12"PWRGD_PVDD33_S5";
13"GND\g";
14"GND\g";
15"GND\g";
16"PVDD_33_S5\g";
17"PVDD_33_S5_VCC\g";
18"P12V_AUX\g";
19"SW_PVDD_33_S5_SW";
20"SW_PVDD_33_S5_BST_R";
21"SW_PVDD_33_S5_BST";
22"PVDD_33_S5_REF";
23"PVDD_33_S5_MODE";
24"PVDD33_S5_EN";
25"PVDD_33_S5_FB";
26"PVDD_33_S5_CS";
27"SW_P12V_AUX_PVDD_33_S5_FLT";
%"UNIVERSAL_GND"
"1","(-8450,2225)","0","pure_quanta_power","I1";
;
CDS_LIB"pure_quanta_power"
HDL_POWER"GND";
"A"1;
%"Q_INDUCTOR"
"1","(-10050,4675)","0","pure_quanta","I10";
;
LOCATION"PL71"
SEC"1"
MATERIAL"IND"
VALUE"BLM18SN220TN1D/8000MA"
PACK_TYPE"SMLF"
CDS_LIB"pure_quanta"
NEEDS_NO_SIZE"TRUE"
SEC_TYPE"SMLF"
PART_NUMBER"CX220TN1001";
"1"
$PN"1"18;
"2"
$PN"2"27;
%"UNIVERSAL_GND"
"1","(-9175,4100)","0","pure_quanta_power","I11";
;
CDS_LIB"pure_quanta_power"
HDL_POWER"GND";
"A"13;
%"Q_CAP"
"1","(-9025,4500)","0","pure_quanta","I12";
;
LOCATION"PC119"
SEC"1"
PACK_TYPE"C0805"
VOLTAGE"16V"
TOLERANCE"20%"
MATERIAL"X6S"
VALUE"22UF"
CDS_LIB"pure_quanta"
SEC_TYPE"C0805"
PART_NUMBER"CH6223MEA01";
"B"
$PN"2"13;
"A"
$PN"1"27;
%"Q_CAP"
"1","(-8675,4475)","0","pure_quanta","I13";
;
LOCATION"PC120"
SEC"1"
PACK_TYPE"C0805"
VOLTAGE"16V"
VALUE"22UF"
TOLERANCE"20%"
MATERIAL"X6S"
SEC_TYPE"C0805"
CDS_LIB"pure_quanta"
PART_NUMBER"CH6223MEA01";
"B"
$PN"2"13;
"A"
$PN"1"27;
%"UNIVERSAL_GND"
"1","(-7875,2300)","0","pure_quanta_power","I14";
;
CDS_LIB"pure_quanta_power"
HDL_POWER"GND";
"A"2;
%"Q_RES"
"2","(-7875,2575)","0","pure_quanta","I15";
;
LOCATION"PR452"
SEC"1"
PACK_TYPE"0402LF"
WATTAGE"1/16W"
MATERIAL"CHIP"
TOLERANCE"1%"
VALUE"6.98K"
SEC_TYPE"0402LF"
CDS_LIB"pure_quanta"
PART_NUMBER"CS26982FB08";
"A"
$PN"1"26;
"B"
$PN"2"2;
%"UNIVERSAL_GND"
"1","(-8225,3225)","0","pure_quanta_power","I16";
;
CDS_LIB"pure_quanta_power"
HDL_POWER"GND";
"A"3;
%"Q_RES"
"1","(-7950,3400)","0","pure_quanta","I17";
;
LOCATION"PR6000"
$SEC"1"
CDS_SEC"1"
PACK_TYPE"0402LF"
TOLERANCE"5%"
MATERIAL"CHIP"
WATTAGE"1/16W"
VALUE"0"
CDS_LIB"pure_quanta"
PART_NUMBER"CS00002JB13";
"B"
$PN"2"23;
"A"
$PN"1"3;
%"UNIVERSAL_GND"
"1","(-6375,2550)","0","pure_quanta_power","I18";
;
CDS_LIB"pure_quanta_power"
HDL_POWER"GND";
"A"14;
%"Q_CAP"
"1","(-6125,2750)","0","pure_quanta","I19";
;
LOCATION"PC127"
SEC"1"
VOLTAGE"25V"
PACK_TYPE"0402"
VALUE"0.1UF"
TOLERANCE"10%"
MATERIAL"X7R"
SEC_TYPE"0402"
CDS_LIB"pure_quanta"
PART_NUMBER"CH4104K1B00";
"B"
$PN"2"4;
"A"
$PN"1"22;
%"Q_CAP"
"1","(-8450,2500)","2","pure_quanta","I2";
;
LOCATION"PC118"
SEC"1"
VALUE"1UF"
MATERIAL"X6S"
TOLERANCE"10%"
VOLTAGE"25V"
PACK_TYPE"C0402"
SIGNAL_MODEL"DEFAULT_CAPACITOR_100000PF_2_1"
CDS_LIB"pure_quanta"
SEC_TYPE"C0402"
PART_NUMBER"CH5104KEB02";
"B"
$PN"2"1;
"A"
$PN"1"17;
%"UNIVERSAL_GND"
"1","(-6125,2550)","0","pure_quanta_power","I20";
;
CDS_LIB"pure_quanta_power"
HDL_POWER"GND";
"A"4;
%"UNIVERSAL_GND"
"1","(-5775,2550)","0","pure_quanta_power","I21";
;
CDS_LIB"pure_quanta_power"
HDL_POWER"GND";
"A"5;
%"UNIVERSAL_GND"
"1","(-5175,2125)","0","pure_quanta_power","I22";
;
CDS_LIB"pure_quanta_power"
HDL_POWER"GND";
"A"6;
%"Q_RES"
"2","(-5175,2400)","2","pure_quanta","I23";
;
LOCATION"PR454"
SEC"1"
PACK_TYPE"0402LF"
MATERIAL"CHIP"
WATTAGE"1/16W"
TOLERANCE"1%"
VALUE"12.4K"
CDS_LIB"pure_quanta"
SEC_TYPE"0402LF"
PART_NUMBER"CS31242FB02";
"A"
$PN"1"25;
"B"
$PN"2"6;
%"Q_CAP"
"1","(-4225,2250)","1","pure_quanta","I24";
;
LOCATION"PC132"
SEC"1"
PACK_TYPE"0402"
VOLTAGE"50V"
VALUE"100PF"
TOLERANCE"5%"
MATERIAL"NPO"
SEC_TYPE"0402"
CDS_LIB"pure_quanta"
PART_NUMBER"CH11006JB00";
"B"
$PN"2"16;
"A"
$PN"1"25;
%"Q_RES"
"1","(-4225,2650)","0","pure_quanta","I25";
;
LOCATION"PR455"
SEC"1"
PACK_TYPE"0402LF"
MATERIAL"CHIP"
WATTAGE"1/16W"
TOLERANCE"1%"
VALUE"56K"
CDS_LIB"pure_quanta"
SEC_TYPE"0402LF"
PART_NUMBER"CS35602FB00";
"B"
$PN"2"16;
"A"
$PN"1"25;
%"Q_CAP"
"1","(-4575,3300)","0","pure_quanta","I27";
;
LOCATION"PC129"
SEC"1"
VALUE"22UF"
MATERIAL"X6S"
PACK_TYPE"C0805"
VOLTAGE"16V"
TOLERANCE"20%"
SEC_TYPE"C0805"
CDS_LIB"pure_quanta"
PART_NUMBER"CH6223MEA01";
"B"
$PN"2"15;
"A"
$PN"1"16;
%"Q_CAP"
"1","(-4275,3300)","0","pure_quanta","I28";
;
LOCATION"PC130"
SEC"1"
MATERIAL"X6S"
PACK_TYPE"C0805"
TOLERANCE"20%"
VALUE"22UF"
VOLTAGE"16V"
SEC_TYPE"C0805"
CDS_LIB"pure_quanta"
PART_NUMBER"CH6223MEA01";
"B"
$PN"2"15;
"A"
$PN"1"16;
%"Q_CAP"
"1","(-8275,4475)","0","pure_quanta","I29";
;
LOCATION"PC123"
SEC"1"
TOLERANCE"20%"
VOLTAGE"16V"
VALUE"22UF"
PACK_TYPE"C0805"
MATERIAL"X6S"
SEC_TYPE"C0805"
CDS_LIB"pure_quanta"
PART_NUMBER"CH6223MEA01";
"B"
$PN"2"13;
"A"
$PN"1"27;
%"Q_CAP"
"1","(-7850,4475)","0","pure_quanta","I30";
;
LOCATION"PC126"
$SEC"1"
CDS_SEC"1"
TOLERANCE"10%"
MATERIAL"X6S"
PACK_TYPE"C0402"
VOLTAGE"25V"
VALUE"1UF"
CDS_LIB"pure_quanta"
PART_NUMBER"CH5104KEB02";
"B"
$PN"2"13;
"A"
$PN"1"27;
%"Q_RES"
"2","(-6375,4450)","0","pure_quanta","I31";
;
LOCATION"R453"
SEC"1"
PACK_TYPE"0402LF"
WATTAGE"1/16W"
TOLERANCE"5%"
VALUE"10K"
CDS_LIB"pure_quanta"
SEC_TYPE"0402LF"
MATERIAL"CHIP"
PART_NUMBER"CS31002JB08";
"A"
$PN"1"7;
"B"
$PN"2"12;
%"UNIVERSAL_POWER"
"1","(-6375,4750)","2","pure_quanta_power","I32";
;
HDL_POWER"PVDD_33_S5_VCC"
CDS_LIB"pure_quanta_power";
"A"7;
%"Q_RES"
"1","(-5225,4100)","0","pure_quanta","I33";
;
LOCATION"R225"
$SEC"1"
CDS_SEC"1"
VALUE"33"
PACK_TYPE"0402LF"
TOLERANCE"5%"
MATERIAL"CHIP"
WATTAGE"1/16W"
BOM_COST"MEM"
CDS_LIB"pure_quanta"
PART_NUMBER"CS03302JB10";
"B"
$PN"2"11;
"A"
$PN"1"12;
%"UNIVERSAL_GND"
"1","(-3275,2900)","0","pure_quanta_power","I34";
;
CDS_LIB"pure_quanta_power"
HDL_POWER"GND";
"A"15;
%"Q_CAP"
"1","(-3975,3300)","0","pure_quanta","I35";
;
LOCATION"PC134"
SEC"1"
TOLERANCE"20%"
MATERIAL"X6S"
VALUE"22UF"
VOLTAGE"16V"
PACK_TYPE"C0805"
SEC_TYPE"C0805"
CDS_LIB"pure_quanta"
PART_NUMBER"CH6223MEA01";
"B"
$PN"2"15;
"A"
$PN"1"16;
%"Q_CAP"
"1","(-3675,3300)","0","pure_quanta","I36";
;
LOCATION"PC135"
SEC"1"
MATERIAL"X6S"
TOLERANCE"20%"
VALUE"22UF"
VOLTAGE"16V"
PACK_TYPE"C0805"
SEC_TYPE"C0805"
CDS_LIB"pure_quanta"
PART_NUMBER"CH6223MEA01";
"B"
$PN"2"15;
"A"
$PN"1"16;
%"Q_CAP"
"1","(-3275,3300)","0","pure_quanta","I37";
;
LOCATION"PC136"
SEC"1"
PACK_TYPE"0402"
VOLTAGE"25V"
MATERIAL"X7R"
VALUE"0.1UF"
TOLERANCE"10%"
CDS_LIB"pure_quanta"
SEC_TYPE"0402"
PART_NUMBER"CH4104K1B00";
"B"
$PN"2"15;
"A"
$PN"1"16;
%"UNIVERSAL_POWER"
"1","(-2825,3750)","0","pure_quanta_power","I38";
;
HDL_POWER"PVDD_33_S5"
CDS_LIB"pure_quanta_power";
"A"16;
%"UNIVERSAL_POWER"
"1","(-8450,3050)","0","pure_quanta_power","I4";
;
HDL_POWER"PVDD_33_S5_VCC"
CDS_LIB"pure_quanta_power";
"A"17;
%"Q_CAP"
"1","(-5425,3725)","0","pure_quanta","I40";
;
LOCATION"PC128"
SEC"1"
VOLTAGE"25V"
VALUE"0.1UF"
PACK_TYPE"0402"
MATERIAL"X7R"
TOLERANCE"10%"
SEC_TYPE"0402"
CDS_LIB"pure_quanta"
PART_NUMBER"CH4104K1B00";
"B"
$PN"2"19;
"A"
$PN"1"20;
%"MPQ8633AGLEC807Z"
"1","(-6875,3425)","0","pure_quanta","I41";
;
LOCATION"PU55"
SEC"1"
MATERIAL"IC"
VALUE"MPQ8633AGLE-C807-Z"
SEC_TYPE""
NEEDS_NO_SIZE"TRUE"
PART_TYPE"SMLF"
CDS_LMAN_SYM_OUTLINE"-250,725,250,-725"
CDS_LIB"pure_quanta"
PART_NUMBER"AL008633007";
"VIN2"
$PN"21"27;
"CS"
$PN"3"26;
"MODE"
$PN"4"23;
"TRK_REF"
$PN"5"22;
"SW"
$PN"20"19;
"RGND"
$PN"6"5;
"VCC"
$PN"19"17;
"AGND"
$PN"2"14;
"FB"
$PN"7"25;
"BST"
$PN"1"21;
"EN"
$PN"8"24;
"PGND"
$PN"11_18"14;
"PGOOD"
$PN"9"12;
"VIN1"
$PN"10"27;
%"UNIVERSAL_GND"
"1","(-4850,3750)","0","pure_quanta_power","I42";
;
CDS_LIB"pure_quanta_power"
HDL_POWER"GND";
"A"8;
%"Q_CAP"
"1","(-4850,3950)","0","pure_quanta","I43";
;
LOCATION"C5002"
$SEC"1"
CDS_SEC"1"
PACK_TYPE"0402"
VOLTAGE"50V"
VALUE"1000PF"
MATERIAL"X7R"
TOLERANCE"5%"
CDS_LIB"pure_quanta"
PART_NUMBER"TMP_QCH21006JB10";
"B"
$PN"2"8;
"A"
$PN"1"11;
%"Q_CAP"
"1","(-9275,4500)","0","pure_quanta","I44";
;
LOCATION"PC8000"
$SEC"1"
CDS_SEC"1"
PACK_TYPE"C0805"
TOLERANCE"20%"
MATERIAL"X6S"
VALUE"22UF"
VOLTAGE"16V"
CDS_LIB"pure_quanta"
PART_NUMBER"CH6223MEA01";
"B"
$PN"2"13;
"A"
$PN"1"27;
%"Q_CAP"
"1","(-9600,4500)","0","pure_quanta","I45";
;
LOCATION"PC8001"
$SEC"1"
CDS_SEC"1"
MATERIAL"X6S"
VOLTAGE"16V"
TOLERANCE"20%"
VALUE"22UF"
PACK_TYPE"C0805"
CDS_LIB"pure_quanta"
PART_NUMBER"CH6223MEA01";
"B"
$PN"2"13;
"A"
$PN"1"27;
%"Q_RES"
"1","(-5750,3900)","0","pure_quanta","I46";
;
LOCATION"PR8000"
$SEC"1"
CDS_SEC"1"
WATTAGE"1/16W"
MATERIAL"CHIP"
VALUE"0"
TOLERANCE"5%"
PACK_TYPE"0402LF"
CDS_LIB"pure_quanta"
PART_NUMBER"CS00002JB13";
"B"
$PN"2"20;
"A"
$PN"1"21;
%"Q_INDUCTOR"
"1","(-4850,3625)","0","pure_quanta","I47";
;
LOCATION"PL72"
SEC"1"
VALUE"1.5UH"
PACK_TYPE"SMLF"
MATERIAL"IND"
CDS_LIB"pure_quanta"
NEEDS_NO_SIZE"TRUE"
SEC_TYPE"SMLF"
PART_NUMBER"CV-15I0MZ28";
"1"
$PN"1"19;
"2"
$PN"2"16;
%"Q_CAP"
"1","(-8475,3425)","2","pure_quanta","I5";
;
LOCATION"C348"
$SEC"1"
CDS_SEC"1"
VALUE"0.1UF"
PACK_TYPE"0402"
VOLTAGE"25V"
TOLERANCE"10%"
MATERIAL"EMPTY"
CDS_LIB"pure_quanta"
PART_NUMBER"CH4104K1B00";
"B"
$PN"2"9;
"A"
$PN"1"24;
%"UNIVERSAL_GND"
"1","(-8475,3225)","0","pure_quanta_power","I6";
;
CDS_LIB"pure_quanta_power"
HDL_POWER"GND";
"A"9;
%"UNIVERSAL_GND"
"1","(-10550,4125)","0","pure_quanta_power","I7";
;
CDS_LIB"pure_quanta_power"
HDL_POWER"GND";
"A"10;
%"Q_CAP"
"1","(-10550,4450)","0","pure_quanta","I8";
;
LOCATION"PC6000"
$SEC"1"
CDS_SEC"1"
TOLERANCE"10%"
VALUE"0.1UF"
MATERIAL"X6S"
VOLTAGE"25V"
PACK_TYPE"C0402"
CDS_LIB"pure_quanta"
PART_NUMBER"CH4104KEB00";
"B"
$PN"2"10;
"A"
$PN"1"18;
%"UNIVERSAL_POWER"
"1","(-10450,4850)","0","pure_quanta_power","I9";
;
HDL_POWER"P12V_AUX"
CDS_LIB"pure_quanta_power";
"A"18;
END.
